(kicad_pcb
	(version 20241229)
	(generator "pcbnew")
	(generator_version "9.0")
	(general
		(thickness 1.62)
		(legacy_teardrops no)
	)
	(paper "A3")
	(title_block
		(title "COM Express 7 Baseboard")
		(date "2025-02-04")
		(rev "1.1.2")
		(company "Antmicro Ltd")
		(comment 1 "www.antmicro.com")
		(comment 9 "footprints 720-724 of 802")
	)
	(layers
		(0 "F.Cu" signal)
		(4 "In1.Cu" signal)
		(6 "In2.Cu" signal)
		(8 "In3.Cu" signal)
		(10 "In4.Cu" signal)
		(12 "In5.Cu" signal)
		(14 "In6.Cu" signal)
		(2 "B.Cu" signal)
		(9 "F.Adhes" user "F.Adhesive")
		(11 "B.Adhes" user "B.Adhesive")
		(13 "F.Paste" user)
		(15 "B.Paste" user)
		(5 "F.SilkS" user "F.Silkscreen")
		(7 "B.SilkS" user "B.Silkscreen")
		(1 "F.Mask" user)
		(3 "B.Mask" user)
		(17 "Dwgs.User" user "User.Drawings")
		(19 "Cmts.User" user "User.Comments")
		(21 "Eco1.User" user "User.Eco1")
		(23 "Eco2.User" user "User.Eco2")
		(25 "Edge.Cuts" user)
		(27 "Margin" user)
		(31 "F.CrtYd" user "F.Courtyard")
		(29 "B.CrtYd" user "B.Courtyard")
		(35 "F.Fab" user)
		(33 "B.Fab" user)
	)
	(footprint "antmicro-footprints:C_0402_1005Metric"
		(layer "B.Cu")
		(at 100.25 96.56 180)
		(descr "Capacitor SMD 0402")
		(tags "capacitor SMD 0402")
		(property "Reference" "C5"
			(at -0.775 -1.36 0)
			(layer "B.SilkS")
			(effects
				(font
					(size 0.7 0.7)
					(thickness 0.15)
				)
				(justify left bottom mirror)
			)
		)
		(property "Value" "C_100n_0402"
			(at -1.022927 -2.155213 0)
			(layer "B.Fab")
			(effects
				(font
					(size 0.7 0.7)
					(thickness 0.15)
				)
				(justify left bottom mirror)
			)
		)
		(property "Datasheet" "https://www.murata.com/products/productdetail?partno=GRM155R61H104KE14%23"
			(at 0 0 180)
			(layer "F.Fab")
			(hide yes)
			(effects
				(font
					(size 1.27 1.27)
					(thickness 0.15)
				)
			)
		)
		(property "Author" "Antmicro"
			(at 200.5 193.12 0)
			(layer "B.Fab")
			(hide yes)
			(effects
				(font
					(size 1 1)
					(thickness 0.15)
				)
				(justify mirror)
			)
		)
		(property "Dielectric" "X5R"
			(at 200.5 193.12 0)
			(layer "B.Fab")
			(hide yes)
			(effects
				(font
					(size 1 1)
					(thickness 0.15)
				)
				(justify mirror)
			)
		)
		(property "License" "Apache-2.0"
			(at 200.5 193.12 0)
			(layer "B.Fab")
			(hide yes)
			(effects
				(font
					(size 1 1)
					(thickness 0.15)
				)
				(justify mirror)
			)
		)
		(property "MPN" "GRM155R61H104KE14D"
			(at 200.5 193.12 0)
			(layer "B.Fab")
			(hide yes)
			(effects
				(font
					(size 1 1)
					(thickness 0.15)
				)
				(justify mirror)
			)
		)
		(property "Manufacturer" "Murata"
			(at 200.5 193.12 0)
			(layer "B.Fab")
			(hide yes)
			(effects
				(font
					(size 1 1)
					(thickness 0.15)
				)
				(justify mirror)
			)
		)
		(property "Public" "False"
			(at 200.5 193.12 0)
			(layer "B.Fab")
			(hide yes)
			(effects
				(font
					(size 1 1)
					(thickness 0.15)
				)
				(justify mirror)
			)
		)
		(property "Val" "100n"
			(at 200.5 193.12 0)
			(layer "B.Fab")
			(hide yes)
			(effects
				(font
					(size 1 1)
					(thickness 0.15)
				)
				(justify mirror)
			)
		)
		(property "Voltage" "50V"
			(at 200.5 193.12 0)
			(layer "B.Fab")
			(hide yes)
			(effects
				(font
					(size 1 1)
					(thickness 0.15)
				)
				(justify mirror)
			)
		)
		(sheetname "2xUSB3.0+RJ45")
		(sheetfile "usb3+rj45.kicad_sch")
		(attr smd)
		(fp_rect
			(start -0.925 0.47)
			(end 0.925 -0.47)
			(stroke
				(width 0.05)
				(type default)
			)
			(fill no)
			(layer "B.CrtYd")
		)
		(fp_line
			(start 0.504 0.25)
			(end -0.494 0.25)
			(stroke
				(width 0.15)
				(type solid)
			)
			(layer "B.Fab")
		)
		(fp_line
			(start 0.504 -0.248)
			(end 0.504 0.25)
			(stroke
				(width 0.15)
				(type solid)
			)
			(layer "B.Fab")
		)
		(fp_line
			(start -0.494 0.25)
			(end -0.494 -0.248)
			(stroke
				(width 0.15)
				(type solid)
			)
			(layer "B.Fab")
		)
		(fp_line
			(start -0.494 -0.248)
			(end 0.504 -0.248)
			(stroke
				(width 0.15)
				(type solid)
			)
			(layer "B.Fab")
		)
		(pad "1" smd roundrect
			(at -0.48 0 180)
			(size 0.59 0.64)
			(layers "B.Cu" "B.Mask" "B.Paste")
			(roundrect_rratio 0.25)
			(net 579 "/2xUSB3.0+RJ45/SH")
			(pintype "passive")
			(teardrops
				(best_length_ratio 0.2)
				(max_length 1)
				(best_width_ratio 0.9)
				(max_width 2)
				(curved_edges yes)
				(filter_ratio 0.9)
				(enabled yes)
				(allow_two_segments yes)
				(prefer_zone_connections yes)
			)
		)
		(pad "2" smd roundrect
			(at 0.48 0 180)
			(size 0.59 0.64)
			(layers "B.Cu" "B.Mask" "B.Paste")
			(roundrect_rratio 0.25)
			(net 1 "GND")
			(pintype "passive")
			(teardrops
				(best_length_ratio 0.2)
				(max_length 1)
				(best_width_ratio 0.9)
				(max_width 2)
				(curved_edges yes)
				(filter_ratio 0.9)
				(enabled yes)
				(allow_two_segments yes)
				(prefer_zone_connections yes)
			)
		)
	)
	(footprint "antmicro-footprints:C_0402_1005Metric"
		(layer "B.Cu")
		(at 152.95 141.86 180)
		(descr "Capacitor SMD 0402")
		(tags "capacitor SMD 0402")
		(property "Reference" "C169"
			(at -3.7 -0.4 0)
			(layer "B.SilkS")
			(effects
				(font
					(size 0.7 0.7)
					(thickness 0.15)
				)
				(justify left bottom mirror)
			)
		)
		(property "Value" "C_100n_0402"
			(at -1.022927 -2.155213 0)
			(layer "B.Fab")
			(effects
				(font
					(size 0.7 0.7)
					(thickness 0.15)
				)
				(justify left bottom mirror)
			)
		)
		(property "Datasheet" "https://www.murata.com/products/productdetail?partno=GRM155R61H104KE14%23"
			(at 0 0 180)
			(layer "F.Fab")
			(hide yes)
			(effects
				(font
					(size 1.27 1.27)
					(thickness 0.15)
				)
			)
		)
		(property "Author" "Antmicro"
			(at 305.9 283.72 0)
			(layer "B.Fab")
			(hide yes)
			(effects
				(font
					(size 1 1)
					(thickness 0.15)
				)
				(justify mirror)
			)
		)
		(property "Dielectric" "X5R"
			(at 305.9 283.72 0)
			(layer "B.Fab")
			(hide yes)
			(effects
				(font
					(size 1 1)
					(thickness 0.15)
				)
				(justify mirror)
			)
		)
		(property "License" "Apache-2.0"
			(at 305.9 283.72 0)
			(layer "B.Fab")
			(hide yes)
			(effects
				(font
					(size 1 1)
					(thickness 0.15)
				)
				(justify mirror)
			)
		)
		(property "MPN" "GRM155R61H104KE14D"
			(at 305.9 283.72 0)
			(layer "B.Fab")
			(hide yes)
			(effects
				(font
					(size 1 1)
					(thickness 0.15)
				)
				(justify mirror)
			)
		)
		(property "Manufacturer" "Murata"
			(at 305.9 283.72 0)
			(layer "B.Fab")
			(hide yes)
			(effects
				(font
					(size 1 1)
					(thickness 0.15)
				)
				(justify mirror)
			)
		)
		(property "Public" "False"
			(at 305.9 283.72 0)
			(layer "B.Fab")
			(hide yes)
			(effects
				(font
					(size 1 1)
					(thickness 0.15)
				)
				(justify mirror)
			)
		)
		(property "Val" "100n"
			(at 305.9 283.72 0)
			(layer "B.Fab")
			(hide yes)
			(effects
				(font
					(size 1 1)
					(thickness 0.15)
				)
				(justify mirror)
			)
		)
		(property "Voltage" "50V"
			(at 305.9 283.72 0)
			(layer "B.Fab")
			(hide yes)
			(effects
				(font
					(size 1 1)
					(thickness 0.15)
				)
				(justify mirror)
			)
		)
		(sheetname "KR to SFI #1")
		(sheetfile "kr_sfi.kicad_sch")
		(attr smd)
		(fp_rect
			(start -0.925 0.47)
			(end 0.925 -0.47)
			(stroke
				(width 0.05)
				(type default)
			)
			(fill no)
			(layer "B.CrtYd")
		)
		(fp_line
			(start 0.504 0.25)
			(end -0.494 0.25)
			(stroke
				(width 0.15)
				(type solid)
			)
			(layer "B.Fab")
		)
		(fp_line
			(start 0.504 -0.248)
			(end 0.504 0.25)
			(stroke
				(width 0.15)
				(type solid)
			)
			(layer "B.Fab")
		)
		(fp_line
			(start -0.494 0.25)
			(end -0.494 -0.248)
			(stroke
				(width 0.15)
				(type solid)
			)
			(layer "B.Fab")
		)
		(fp_line
			(start -0.494 -0.248)
			(end 0.504 -0.248)
			(stroke
				(width 0.15)
				(type solid)
			)
			(layer "B.Fab")
		)
		(pad "1" smd roundrect
			(at -0.48 0 180)
			(size 0.59 0.64)
			(layers "B.Cu" "B.Mask" "B.Paste")
			(roundrect_rratio 0.25)
			(net 1 "GND")
			(pintype "passive")
			(teardrops
				(best_length_ratio 0.2)
				(max_length 1)
				(best_width_ratio 0.9)
				(max_width 2)
				(curved_edges yes)
				(filter_ratio 0.9)
				(enabled yes)
				(allow_two_segments yes)
				(prefer_zone_connections yes)
			)
		)
		(pad "2" smd roundrect
			(at 0.48 0 180)
			(size 0.59 0.64)
			(layers "B.Cu" "B.Mask" "B.Paste")
			(roundrect_rratio 0.25)
			(net 78 "+1V8")
			(pintype "passive")
			(teardrops
				(best_length_ratio 0.2)
				(max_length 1)
				(best_width_ratio 0.9)
				(max_width 2)
				(curved_edges yes)
				(filter_ratio 0.9)
				(enabled yes)
				(allow_two_segments yes)
				(prefer_zone_connections yes)
			)
		)
	)
	(footprint "antmicro-footprints:USON-10_2.5x1mm_P0.5mm"
		(layer "B.Cu")
		(at 104.77 159.61)
		(descr "USON-10 2.5x1mm_ Pitch 0.5mm")
		(tags "USON-10 2.5x1mm Pitch 0.5mm")
		(property "Reference" "U11"
			(at 1.73 1.15 90)
			(layer "B.SilkS")
			(effects
				(font
					(size 0.7 0.7)
					(thickness 0.15)
				)
				(justify right bottom mirror)
			)
		)
		(property "Value" "ESD204DQAR"
			(at 0.018 -2.499 0)
			(layer "B.Fab")
			(effects
				(font
					(size 0.7 0.7)
					(thickness 0.15)
				)
				(justify right bottom mirror)
			)
		)
		(property "Datasheet" "https://www.ti.com/lit/ds/symlink/esd204.pdf?ts=1706004844383&ref_url=https%253A%252F%252Fwww.ti.com%252Finterface%252Fdiodes%252Fesd-protection-diodes%252Fproducts.html"
			(at 0 0 0)
			(layer "F.Fab")
			(hide yes)
			(effects
				(font
					(size 1.27 1.27)
					(thickness 0.15)
				)
			)
		)
		(property "Author" "Antmicro"
			(at 0 0 0)
			(layer "B.Fab")
			(hide yes)
			(effects
				(font
					(size 1 1)
					(thickness 0.15)
				)
				(justify mirror)
			)
		)
		(property "License" "Apache-2.0"
			(at 0 0 0)
			(layer "B.Fab")
			(hide yes)
			(effects
				(font
					(size 1 1)
					(thickness 0.15)
				)
				(justify mirror)
			)
		)
		(property "MPN" "ESD204DQAR"
			(at 0 0 0)
			(layer "B.Fab")
			(hide yes)
			(effects
				(font
					(size 1 1)
					(thickness 0.15)
				)
				(justify mirror)
			)
		)
		(property "Manufacturer" "Texas Instruments"
			(at 0 0 0)
			(layer "B.Fab")
			(hide yes)
			(effects
				(font
					(size 1 1)
					(thickness 0.15)
				)
				(justify mirror)
			)
		)
		(sheetname "OCuLink")
		(sheetfile "oculink.kicad_sch")
		(attr smd)
		(fp_line
			(start -0.5 -1.398)
			(end 0.498 -1.398)
			(stroke
				(width 0.15)
				(type solid)
			)
			(layer "B.SilkS")
		)
		(fp_line
			(start -0.5 1.401)
			(end 0.498 1.401)
			(stroke
				(width 0.15)
				(type solid)
			)
			(layer "B.SilkS")
		)
		(fp_circle
			(center -0.68 1.27)
			(end -0.63 1.27)
			(stroke
				(width 0.15)
				(type solid)
			)
			(fill yes)
			(layer "B.SilkS")
		)
		(fp_rect
			(start -0.8 1.5)
			(end 0.8 -1.499)
			(stroke
				(width 0.05)
				(type solid)
			)
			(fill no)
			(layer "B.CrtYd")
		)
		(fp_line
			(start -0.5 -1.249)
			(end -0.5 1)
			(stroke
				(width 0.15)
				(type solid)
			)
			(layer "B.Fab")
		)
		(fp_line
			(start -0.5 1)
			(end -0.25 1.25)
			(stroke
				(width 0.15)
				(type solid)
			)
			(layer "B.Fab")
		)
		(fp_line
			(start -0.25 1.25)
			(end 0.498 1.25)
			(stroke
				(width 0.15)
				(type solid)
			)
			(layer "B.Fab")
		)
		(fp_line
			(start 0.498 -1.249)
			(end -0.5 -1.249)
			(stroke
				(width 0.15)
				(type solid)
			)
			(layer "B.Fab")
		)
		(fp_line
			(start 0.498 -1.249)
			(end 0.498 1.25)
			(stroke
				(width 0.15)
				(type solid)
			)
			(layer "B.Fab")
		)
		(pad "1" smd roundrect
			(at -0.387 1 90)
			(size 0.25 0.55)
			(layers "B.Cu" "B.Mask" "B.Paste")
			(roundrect_rratio 0.25)
			(net 104 "/OCuLink/PCIe_{x4}.TX2+")
			(pintype "passive")
			(teardrops
				(best_length_ratio 0.2)
				(max_length 1)
				(best_width_ratio 0.9)
				(max_width 2)
				(curved_edges yes)
				(filter_ratio 0.9)
				(enabled yes)
				(allow_two_segments yes)
				(prefer_zone_connections yes)
			)
		)
		(pad "2" smd roundrect
			(at -0.387 0.5 90)
			(size 0.25 0.55)
			(layers "B.Cu" "B.Mask" "B.Paste")
			(roundrect_rratio 0.25)
			(net 97 "/OCuLink/PCIe_{x4}.TX2-")
			(pintype "passive")
			(teardrops
				(best_length_ratio 0.2)
				(max_length 1)
				(best_width_ratio 0.9)
				(max_width 2)
				(curved_edges yes)
				(filter_ratio 0.9)
				(enabled yes)
				(allow_two_segments yes)
				(prefer_zone_connections yes)
			)
		)
		(pad "3" smd roundrect
			(at -0.387 0 90)
			(size 0.4 0.55)
			(layers "B.Cu" "B.Mask" "B.Paste")
			(roundrect_rratio 0.25)
			(net 1 "GND")
			(pintype "power_in")
			(teardrops
				(best_length_ratio 0.2)
				(max_length 1)
				(best_width_ratio 0.9)
				(max_width 2)
				(curved_edges yes)
				(filter_ratio 0.9)
				(enabled yes)
				(allow_two_segments yes)
				(prefer_zone_connections yes)
			)
		)
		(pad "4" smd roundrect
			(at -0.387 -0.498 90)
			(size 0.25 0.55)
			(layers "B.Cu" "B.Mask" "B.Paste")
			(roundrect_rratio 0.25)
			(net 106 "/OCuLink/PCIe_{x4}.TX3+")
			(pintype "passive")
			(teardrops
				(best_length_ratio 0.2)
				(max_length 1)
				(best_width_ratio 0.9)
				(max_width 2)
				(curved_edges yes)
				(filter_ratio 0.9)
				(enabled yes)
				(allow_two_segments yes)
				(prefer_zone_connections yes)
			)
		)
		(pad "5" smd roundrect
			(at -0.387 -0.998 90)
			(size 0.25 0.55)
			(layers "B.Cu" "B.Mask" "B.Paste")
			(roundrect_rratio 0.25)
			(net 98 "/OCuLink/PCIe_{x4}.TX3-")
			(pintype "passive")
			(teardrops
				(best_length_ratio 0.2)
				(max_length 1)
				(best_width_ratio 0.9)
				(max_width 2)
				(curved_edges yes)
				(filter_ratio 0.9)
				(enabled yes)
				(allow_two_segments yes)
				(prefer_zone_connections yes)
			)
		)
		(pad "6" smd roundrect
			(at 0.385 -0.998 90)
			(size 0.25 0.55)
			(layers "B.Cu" "B.Mask" "B.Paste")
			(roundrect_rratio 0.25)
			(net 98 "/OCuLink/PCIe_{x4}.TX3-")
			(pintype "passive")
			(teardrops
				(best_length_ratio 0.2)
				(max_length 1)
				(best_width_ratio 0.9)
				(max_width 2)
				(curved_edges yes)
				(filter_ratio 0.9)
				(enabled yes)
				(allow_two_segments yes)
				(prefer_zone_connections yes)
			)
		)
		(pad "7" smd roundrect
			(at 0.385 -0.498 90)
			(size 0.25 0.55)
			(layers "B.Cu" "B.Mask" "B.Paste")
			(roundrect_rratio 0.25)
			(net 106 "/OCuLink/PCIe_{x4}.TX3+")
			(pintype "passive")
			(teardrops
				(best_length_ratio 0.2)
				(max_length 1)
				(best_width_ratio 0.9)
				(max_width 2)
				(curved_edges yes)
				(filter_ratio 0.9)
				(enabled yes)
				(allow_two_segments yes)
				(prefer_zone_connections yes)
			)
		)
		(pad "8" smd roundrect
			(at 0.385 0 90)
			(size 0.4 0.55)
			(layers "B.Cu" "B.Mask" "B.Paste")
			(roundrect_rratio 0.25)
			(net 1 "GND")
			(pintype "passive")
			(teardrops
				(best_length_ratio 0.2)
				(max_length 1)
				(best_width_ratio 0.9)
				(max_width 2)
				(curved_edges yes)
				(filter_ratio 0.9)
				(enabled yes)
				(allow_two_segments yes)
				(prefer_zone_connections yes)
			)
		)
		(pad "9" smd roundrect
			(at 0.385 0.5 90)
			(size 0.25 0.55)
			(layers "B.Cu" "B.Mask" "B.Paste")
			(roundrect_rratio 0.25)
			(net 97 "/OCuLink/PCIe_{x4}.TX2-")
			(pintype "passive")
			(teardrops
				(best_length_ratio 0.2)
				(max_length 1)
				(best_width_ratio 0.9)
				(max_width 2)
				(curved_edges yes)
				(filter_ratio 0.9)
				(enabled yes)
				(allow_two_segments yes)
				(prefer_zone_connections yes)
			)
		)
		(pad "10" smd roundrect
			(at 0.385 1 90)
			(size 0.25 0.55)
			(layers "B.Cu" "B.Mask" "B.Paste")
			(roundrect_rratio 0.25)
			(net 104 "/OCuLink/PCIe_{x4}.TX2+")
			(pintype "passive")
			(teardrops
				(best_length_ratio 0.2)
				(max_length 1)
				(best_width_ratio 0.9)
				(max_width 2)
				(curved_edges yes)
				(filter_ratio 0.9)
				(enabled yes)
				(allow_two_segments yes)
				(prefer_zone_connections yes)
			)
		)
	)
	(footprint "antmicro-footprints:TP_SMD_0.75mm"
		(layer "B.Cu")
		(at 258.949999 87.01 180)
		(property "Reference" "TP14"
			(at 0.399999 -0.45 0)
			(layer "B.SilkS")
			(effects
				(font
					(size 0.7 0.7)
					(thickness 0.15)
				)
				(justify left bottom mirror)
			)
		)
		(property "Value" "TP_0.75mm_SMD"
			(at 0 -1.2 0)
			(layer "B.Fab")
			(effects
				(font
					(size 0.7 0.7)
					(thickness 0.15)
				)
				(justify left bottom mirror)
			)
		)
		(property "Author" "Antmicro"
			(at 517.899998 174.02 0)
			(layer "B.Fab")
			(hide yes)
			(effects
				(font
					(size 1 1)
					(thickness 0.15)
				)
				(justify mirror)
			)
		)
		(property "License" "Apache-2.0"
			(at 517.899998 174.02 0)
			(layer "B.Fab")
			(hide yes)
			(effects
				(font
					(size 1 1)
					(thickness 0.15)
				)
				(justify mirror)
			)
		)
		(property "MPN" ""
			(at 517.899998 174.02 0)
			(layer "B.Fab")
			(hide yes)
			(effects
				(font
					(size 1 1)
					(thickness 0.15)
				)
				(justify mirror)
			)
		)
		(property "Manufacturer" ""
			(at 517.899998 174.02 0)
			(layer "B.Fab")
			(hide yes)
			(effects
				(font
					(size 1 1)
					(thickness 0.15)
				)
				(justify mirror)
			)
		)
		(property "Public" "False"
			(at 517.899998 174.02 0)
			(layer "B.Fab")
			(hide yes)
			(effects
				(font
					(size 1 1)
					(thickness 0.15)
				)
				(justify mirror)
			)
		)
		(sheetname "Misc")
		(sheetfile "misc.kicad_sch")
		(attr exclude_from_pos_files exclude_from_bom)
		(fp_circle
			(center 0 0)
			(end 0.475 0)
			(stroke
				(width 0.05)
				(type default)
			)
			(fill no)
			(layer "B.CrtYd")
		)
		(pad "1" smd circle
			(at 0 0 180)
			(size 0.75 0.75)
			(layers "B.Cu" "B.Mask")
			(net 706 "Net-(U24-GPIO0)")
			(pinfunction "1")
			(pintype "passive")
			(teardrops
				(best_length_ratio 0.4)
				(max_length 1)
				(best_width_ratio 0.9)
				(max_width 2)
				(curved_edges yes)
				(filter_ratio 0.9)
				(enabled yes)
				(allow_two_segments yes)
				(prefer_zone_connections yes)
			)
		)
	)
	(footprint "antmicro-footprints:TP_SMD_0.75mm"
		(layer "B.Cu")
		(at 196.6 163.325)
		(property "Reference" "TP27"
			(at -0.15 -0.825 90)
			(layer "B.SilkS")
			(effects
				(font
					(size 0.7 0.7)
					(thickness 0.15)
				)
				(justify right top mirror)
			)
		)
		(property "Value" "TP_0.75mm_SMD"
			(at 3.225 -53.865 0)
			(layer "B.Fab")
			(hide yes)
			(effects
				(font
					(size 0.7 0.7)
					(thickness 0.15)
				)
				(justify right top mirror)
			)
		)
		(property "Author" "Antmicro"
			(at 413.9 313.02 0)
			(layer "B.Fab")
			(hide yes)
			(effects
				(font
					(size 1 1)
					(thickness 0.15)
				)
				(justify mirror)
			)
		)
		(property "License" "Apache-2.0"
			(at 413.9 313.02 0)
			(layer "B.Fab")
			(hide yes)
			(effects
				(font
					(size 1 1)
					(thickness 0.15)
				)
				(justify mirror)
			)
		)
		(property "MPN" ""
			(at 413.9 313.02 0)
			(layer "B.Fab")
			(hide yes)
			(effects
				(font
					(size 1 1)
					(thickness 0.15)
				)
				(justify mirror)
			)
		)
		(property "Manufacturer" ""
			(at 413.9 313.02 0)
			(layer "B.Fab")
			(hide yes)
			(effects
				(font
					(size 1 1)
					(thickness 0.15)
				)
				(justify mirror)
			)
		)
		(property "Public" "False"
			(at 413.9 313.02 0)
			(layer "B.Fab")
			(hide yes)
			(effects
				(font
					(size 1 1)
					(thickness 0.15)
				)
				(justify mirror)
			)
		)
		(sheetname "Com Express 7 MGMT")
		(sheetfile "com_express_7_mgmt.kicad_sch")
		(attr exclude_from_pos_files exclude_from_bom)
		(fp_circle
			(center 0 0)
			(end 0.475 0)
			(stroke
				(width 0.05)
				(type default)
			)
			(fill no)
			(layer "B.CrtYd")
		)
		(pad "1" smd circle
			(at 0 0)
			(size 0.75 0.75)
			(layers "B.Cu" "B.Mask")
			(net 318 "Net-(J12D-LPC_SERIRQ{slash}~{ESPI_CS1})")
			(pinfunction "1")
			(pintype "passive")
			(teardrops
				(best_length_ratio 0.4)
				(max_length 1)
				(best_width_ratio 0.9)
				(max_width 2)
				(curved_edges yes)
				(filter_ratio 0.9)
				(enabled yes)
				(allow_two_segments yes)
				(prefer_zone_connections yes)
			)
		)
	)
)
